# BASEBOARD_FAB2 (Tioga Pass) — schematic netlist excerpt (pin names and nets, part order shuffled) for the footprints in the layout excerpt that follows; sources: Cadence DE-HDL packaged netlist, KiCad conversion of Wiwynn_Tioga_Pass_MB.brd

C2D35  CAP_A  22.0UF 4V 20% X6S  pkg 0603V  page 76 : A = PVCCIN_CPU1 ; B = GND
R6D5  RES  49.9 1% CHIP  pkg 0402  page 90 : A = PD_CPU0_TEST12 ; B = GND
C9F8  CAP  1000PF 50V 10% X7R  pkg 0402LF  page 238 : A = PWRGD_P1V15_BMC_STBY_R ; B = GND

(kicad_pcb
	(version 20260206)
	(generator "pcbnew")
	(generator_version "10.0")
	(general
		(thickness 1.6)
		(legacy_teardrops no)
	)
	(paper "A4")
	(title_block
		(title "Wiwynn_Tioga_Pass_MB.brd")
		(comment 1 "Tioga Pass / footprints 661-663 of 4770")
	)
	(layers
		(0 "F.Cu" signal "TOP")
		(4 "In1.Cu" signal "L2GND")
		(6 "In2.Cu" signal "L3")
		(8 "In3.Cu" signal "L4GND")
		(10 "In4.Cu" signal "L5")
		(12 "In5.Cu" signal "L6GND")
		(14 "In6.Cu" signal "L7VCC")
		(16 "In7.Cu" signal "L8VCC")
		(18 "In8.Cu" signal "L9GND")
		(20 "In9.Cu" signal "L10")
		(22 "In10.Cu" signal "L11GND")
		(24 "In11.Cu" signal "L12")
		(26 "In12.Cu" signal "L13GND")
		(2 "B.Cu" signal "BOTTOM")
		(9 "F.Adhes" user "F.Adhesive")
		(11 "B.Adhes" user "B.Adhesive")
		(13 "F.Paste" user "Package Geometry/Pastemask Top")
		(15 "B.Paste" user "Package Geometry/Pastemask Bottom")
		(5 "F.SilkS" user "Ref Des/Silkscreen Top")
		(7 "B.SilkS" user "Ref Des/Silkscreen Bottom")
		(1 "F.Mask" user "Board Geometry/Soldermask Top")
		(3 "B.Mask" user "Board Geometry/Soldermask Bottom")
		(17 "Dwgs.User" user "User.Drawings")
		(19 "Cmts.User" user "User.Comments")
		(21 "Eco1.User" user "User.Eco1")
		(23 "Eco2.User" user "User.Eco2")
		(25 "Edge.Cuts" user "Board Geometry/Outline")
		(27 "Margin" user)
		(31 "F.CrtYd" user "Package Geometry/Place Bound Top")
		(29 "B.CrtYd" user "Package Geometry/Place Bound Bottom")
		(35 "F.Fab" user "Ref Des/Assembly Top")
		(33 "B.Fab" user "Ref Des/Assembly Bottom")
	)
	(footprint ""
		(layer "F.Cu")
		(at 99.43084 -73.318116)
		(property "Reference" "C2D35"
			(at 0 0 0)
			(layer "F.SilkS")
			(hide yes)
			(effects
				(font
					(size 1.27 1.27)
				)
			)
		)
		(property "Value" ""
			(at 0 0 0)
			(layer "F.Fab")
			(effects
				(font
					(size 1.27 1.27)
				)
			)
		)
		(duplicate_pad_numbers_are_jumpers no)
		(fp_poly
			(pts
				(xy -0.4953 -0.2032) (xy 0.4953 -0.2032) (xy 0.4953 1.6002) (xy -0.4953 1.6002)
			)
			(stroke
				(width 0)
				(type default)
			)
			(fill no)
			(layer "F.CrtYd")
		)
		(fp_line
			(start -0.4953 -0.2032)
			(end 0.4953 -0.2032)
			(stroke
				(width 0.1)
				(type default)
			)
			(layer "F.Fab")
		)
		(fp_line
			(start -0.4953 1.6002)
			(end -0.4953 -0.2032)
			(stroke
				(width 0.1)
				(type default)
			)
			(layer "F.Fab")
		)
		(fp_line
			(start 0.4953 -0.2032)
			(end 0.4953 1.6002)
			(stroke
				(width 0.1)
				(type default)
			)
			(layer "F.Fab")
		)
		(fp_line
			(start 0.4953 1.6002)
			(end -0.4953 1.6002)
			(stroke
				(width 0.1)
				(type default)
			)
			(layer "F.Fab")
		)
		(pad "1" smd rect
			(at 0 0)
			(size 0.762 0.889)
			(layers "F.Cu" "F.Mask" "F.Paste")
			(net "PVCCIN_CPU1")
		)
		(pad "2" smd rect
			(at 0 1.397)
			(size 0.762 0.889)
			(layers "F.Cu" "F.Mask" "F.Paste")
			(net "GND")
		)
		(zone
			(layer "F.Cu")
			(hatch none 0.5)
			(connect_pads
				(clearance 0)
			)
			(min_thickness 0.25)
			(keepout
				(tracks not_allowed)
				(vias allowed)
				(pads allowed)
				(copperpour not_allowed)
				(footprints allowed)
			)
			(placement
				(enabled no)
				(sheetname "")
			)
			(fill
				(thermal_gap 0.5)
				(thermal_bridge_width 0.5)
				(island_removal_mode 0)
			)
			(polygon
				(pts
					(xy 99.04984 -72.873616) (xy 99.81184 -72.873616) (xy 99.81184 -72.365616) (xy 99.04984 -72.365616)
				)
			)
		)
	)
	(footprint ""
		(layer "F.Cu")
		(at 282.067 -76.835 -90)
		(property "Reference" "R6D5"
			(at 0 0 270)
			(layer "F.SilkS")
			(hide yes)
			(effects
				(font
					(size 1.27 1.27)
				)
			)
		)
		(property "Value" ""
			(at 0 0 270)
			(layer "F.Fab")
			(effects
				(font
					(size 1.27 1.27)
				)
			)
		)
		(duplicate_pad_numbers_are_jumpers no)
		(fp_rect
			(start 0.2794 0.9906)
			(end -0.2794 -0.1016)
			(stroke
				(width 0)
				(type default)
			)
			(fill no)
			(layer "F.CrtYd")
		)
		(fp_line
			(start -0.2794 0.9906)
			(end 0.2794 0.9906)
			(stroke
				(width 0.1)
				(type default)
			)
			(layer "F.Fab")
		)
		(fp_line
			(start 0.2794 0.9906)
			(end 0.2794 -0.1016)
			(stroke
				(width 0.1)
				(type default)
			)
			(layer "F.Fab")
		)
		(fp_line
			(start -0.2794 -0.1016)
			(end -0.2794 0.9906)
			(stroke
				(width 0.1)
				(type default)
			)
			(layer "F.Fab")
		)
		(fp_line
			(start 0.2794 -0.1016)
			(end -0.2794 -0.1016)
			(stroke
				(width 0.1)
				(type default)
			)
			(layer "F.Fab")
		)
		(pad "1" smd rect
			(at 0 0 270)
			(size 0.508 0.508)
			(layers "F.Cu" "F.Mask" "F.Paste")
			(net "PD_CPU0_TEST12")
		)
		(pad "2" smd rect
			(at 0 0.889 270)
			(size 0.508 0.508)
			(layers "F.Cu" "F.Mask" "F.Paste")
			(net "GND")
		)
		(zone
			(layer "F.Cu")
			(hatch none 0.5)
			(connect_pads
				(clearance 0)
			)
			(min_thickness 0.25)
			(keepout
				(tracks not_allowed)
				(vias allowed)
				(pads allowed)
				(copperpour not_allowed)
				(footprints allowed)
			)
			(placement
				(enabled no)
				(sheetname "")
			)
			(fill
				(thermal_gap 0.5)
				(thermal_bridge_width 0.5)
				(island_removal_mode 0)
			)
			(polygon
				(pts
					(xy 281.432 -76.581) (xy 281.813 -76.581) (xy 281.813 -77.089) (xy 281.432 -77.089)
				)
			)
		)
		(zone
			(layer "F.Cu")
			(hatch none 0.5)
			(connect_pads
				(clearance 0)
			)
			(min_thickness 0.25)
			(keepout
				(tracks allowed)
				(vias not_allowed)
				(pads allowed)
				(copperpour not_allowed)
				(footprints allowed)
			)
			(placement
				(enabled no)
				(sheetname "")
			)
			(fill
				(thermal_gap 0.5)
				(thermal_bridge_width 0.5)
				(island_removal_mode 0)
			)
			(polygon
				(pts
					(xy 281.432 -76.581) (xy 281.813 -76.581) (xy 281.813 -77.089) (xy 281.432 -77.089)
				)
			)
		)
	)
	(footprint ""
		(layer "F.Cu")
		(at 460.082392 -37.956998)
		(property "Reference" "C9F8"
			(at 0 0 0)
			(layer "F.SilkS")
			(hide yes)
			(effects
				(font
					(size 1.27 1.27)
				)
			)
		)
		(property "Value" ""
			(at 0 0 0)
			(layer "F.Fab")
			(effects
				(font
					(size 1.27 1.27)
				)
			)
		)
		(duplicate_pad_numbers_are_jumpers no)
		(fp_poly
			(pts
				(xy 0.3048 -0.1016) (xy 0.3048 0.9906) (xy -0.3048 0.9906) (xy -0.3048 -0.1016)
			)
			(stroke
				(width 0)
				(type default)
			)
			(fill no)
			(layer "F.CrtYd")
		)
		(fp_line
			(start -0.3048 -0.1016)
			(end -0.3048 0.9906)
			(stroke
				(width 0.1)
				(type default)
			)
			(layer "F.Fab")
		)
		(fp_line
			(start -0.3048 0.9906)
			(end 0.3048 0.9906)
			(stroke
				(width 0.1)
				(type default)
			)
			(layer "F.Fab")
		)
		(fp_line
			(start 0.3048 -0.1016)
			(end -0.3048 -0.1016)
			(stroke
				(width 0.1)
				(type default)
			)
			(layer "F.Fab")
		)
		(fp_line
			(start 0.3048 0.9906)
			(end 0.3048 -0.1016)
			(stroke
				(width 0.1)
				(type default)
			)
			(layer "F.Fab")
		)
		(pad "1" smd rect
			(at 0 0)
			(size 0.508 0.508)
			(layers "F.Cu" "F.Mask" "F.Paste")
			(net "PWRGD_P1V15_BMC_STBY_R")
		)
		(pad "2" smd rect
			(at 0 0.889)
			(size 0.508 0.508)
			(layers "F.Cu" "F.Mask" "F.Paste")
			(net "GND")
		)
		(zone
			(layer "F.Cu")
			(hatch none 0.5)
			(connect_pads
				(clearance 0)
			)
			(min_thickness 0.25)
			(keepout
				(tracks allowed)
				(vias not_allowed)
				(pads allowed)
				(copperpour not_allowed)
				(footprints allowed)
			)
			(placement
				(enabled no)
				(sheetname "")
			)
			(fill
				(thermal_gap 0.5)
				(thermal_bridge_width 0.5)
				(island_removal_mode 0)
			)
			(polygon
				(pts
					(xy 459.828392 -37.702998) (xy 460.336392 -37.702998) (xy 460.336392 -37.321998) (xy 459.828392 -37.321998)
				)
			)
		)
		(zone
			(layer "F.Cu")
			(hatch none 0.5)
			(connect_pads
				(clearance 0)
			)
			(min_thickness 0.25)
			(keepout
				(tracks not_allowed)
				(vias allowed)
				(pads allowed)
				(copperpour not_allowed)
				(footprints allowed)
			)
			(placement
				(enabled no)
				(sheetname "")
			)
			(fill
				(thermal_gap 0.5)
				(thermal_bridge_width 0.5)
				(island_removal_mode 0)
			)
			(polygon
				(pts
					(xy 459.828392 -37.321998) (xy 460.336392 -37.321998) (xy 460.336392 -37.702998) (xy 459.828392 -37.702998)
				)
			)
		)
	)
)
